#ISCELL
  pure_quanta quanta_title_block_c *
  *
#CELL
  pure_quanta genoa_sp5 *
  page53_i56
#ISCELL
  standard offpage *
  page53_i65
#ISCELL
  standard offpage *
  page53_i66
#ISCELL
  standard offpage *
  page53_i79
#ISCELL
  standard offpage *
  page53_i80
